# Jetson Orin Baseboard OCuLink Expansion — KiCad custom design rules (.kicad_dru)
(version 1)
#----------------------- PCIe -----------------------
(rule "(pcie_outer"
	(layer outer)
	(condition "(A.NetClass == '85Ohm-diff_PCIE')")
	(constraint track_width (opt 0.185mm))
	(constraint diff_pair_gap  (opt 0.145mm))
)